# T6G (Grand Teton) — schematic netlist excerpt (pin names and nets, part order shuffled) for the footprints in the layout excerpt that follows; sources: Cadence DE-HDL packaged netlist, KiCad conversion of 04192023_DAF0TMB3IC0_F0TG_MB_C_brd_V02_OCP.brd

PC552_3  Q_CAP  0.1UF 25V 10% X7R  pkg 0402  page 195 : A = SW_P12V_AUX_PVDDCR_CPU0_P0_FLT ; B = GND
PC437_IOP1_1  Q_CAP  2.2UF 10V 10% X6S  pkg C0402  page 222 : A = PVDDCR_CPU1_P1_PVCC ; B = GND

(kicad_pcb
	(version 20260206)
	(generator "pcbnew")
	(generator_version "10.0")
	(general
		(thickness 1.6)
		(legacy_teardrops no)
	)
	(paper "A4")
	(title_block
		(title "04192023_DAF0TMB3IC0_F0TG_MB_C_brd_V02_OCP.brd")
		(comment 1 "Grand Teton / footprints 1748-1749 of 8354")
	)
	(layers
		(0 "F.Cu" signal "TOP")
		(4 "In1.Cu" signal "GND")
		(6 "In2.Cu" signal "IN1")
		(8 "In3.Cu" signal "GND1")
		(10 "In4.Cu" signal "IN2")
		(12 "In5.Cu" signal "GND2")
		(14 "In6.Cu" signal "IN3")
		(16 "In7.Cu" signal "GND3")
		(18 "In8.Cu" signal "VCC")
		(20 "In9.Cu" signal "VCC1")
		(22 "In10.Cu" signal "GND4")
		(24 "In11.Cu" signal "IN4")
		(26 "In12.Cu" signal "GND5")
		(28 "In13.Cu" signal "IN5")
		(30 "In14.Cu" signal "GND6")
		(32 "In15.Cu" signal "IN6")
		(34 "In16.Cu" signal "GND7")
		(2 "B.Cu" signal "BOTTOM")
		(9 "F.Adhes" user "F.Adhesive")
		(11 "B.Adhes" user "B.Adhesive")
		(13 "F.Paste" user "Package Geometry/Pastemask Top")
		(15 "B.Paste" user "Package Geometry/Pastemask Bottom")
		(5 "F.SilkS" user "Ref Des/Silkscreen Top")
		(7 "B.SilkS" user "Ref Des/Silkscreen Bottom")
		(1 "F.Mask" user "Board Geometry/Soldermask Top")
		(3 "B.Mask" user "Board Geometry/Soldermask Bottom")
		(17 "Dwgs.User" user "User.Drawings")
		(19 "Cmts.User" user "User.Comments")
		(21 "Eco1.User" user "User.Eco1")
		(23 "Eco2.User" user "User.Eco2")
		(25 "Edge.Cuts" user "Board Geometry/Outline")
		(27 "Margin" user)
		(31 "F.CrtYd" user "Package Geometry/Place Bound Top")
		(29 "B.CrtYd" user "Package Geometry/Place Bound Bottom")
		(35 "F.Fab" user "Ref Des/Assembly Top")
		(33 "B.Fab" user "Ref Des/Assembly Bottom")
	)
	(footprint ""
		(layer "F.Cu")
		(at 376.811286 -178.359562 180)
		(property "Reference" "PC552_3"
			(at 0 0 180)
			(layer "F.SilkS")
			(hide yes)
			(effects
				(font
					(size 1.27 1.27)
				)
			)
		)
		(property "Value" ""
			(at 0 0 180)
			(layer "F.Fab")
			(effects
				(font
					(size 1.27 1.27)
				)
			)
		)
		(duplicate_pad_numbers_are_jumpers no)
		(fp_line
			(start 0.7874 0.4064)
			(end -0.7874 0.4064)
			(stroke
				(width 0.1524)
				(type default)
			)
			(layer "F.SilkS")
		)
		(fp_line
			(start 0.7874 -0.4064)
			(end 0.7874 0.4064)
			(stroke
				(width 0.1524)
				(type default)
			)
			(layer "F.SilkS")
		)
		(fp_line
			(start -0.7874 0.4064)
			(end -0.7874 -0.4064)
			(stroke
				(width 0.1524)
				(type default)
			)
			(layer "F.SilkS")
		)
		(fp_line
			(start -0.7874 -0.4064)
			(end 0.7874 -0.4064)
			(stroke
				(width 0.1524)
				(type default)
			)
			(layer "F.SilkS")
		)
		(fp_line
			(start 0.67945 0.3048)
			(end 0.120396 0.3048)
			(stroke
				(width 0.1)
				(type default)
			)
			(layer "F.Fab")
		)
		(fp_line
			(start 0.67945 -0.3048)
			(end 0.67945 0.3048)
			(stroke
				(width 0.1)
				(type default)
			)
			(layer "F.Fab")
		)
		(fp_line
			(start 0.12065 -0.2794)
			(end 0.12065 -0.3048)
			(stroke
				(width 0.1)
				(type default)
			)
			(layer "F.Fab")
		)
		(fp_line
			(start 0.12065 -0.3048)
			(end 0.67945 -0.3048)
			(stroke
				(width 0.1)
				(type default)
			)
			(layer "F.Fab")
		)
		(fp_line
			(start 0.120396 0.3048)
			(end 0.120396 0.2794)
			(stroke
				(width 0.1)
				(type default)
			)
			(layer "F.Fab")
		)
		(fp_line
			(start 0.120396 0.2794)
			(end -0.12065 0.2794)
			(stroke
				(width 0.1)
				(type default)
			)
			(layer "F.Fab")
		)
		(fp_line
			(start -0.12065 0.3048)
			(end -0.67945 0.3048)
			(stroke
				(width 0.1)
				(type default)
			)
			(layer "F.Fab")
		)
		(fp_line
			(start -0.12065 0.2794)
			(end -0.12065 0.3048)
			(stroke
				(width 0.1)
				(type default)
			)
			(layer "F.Fab")
		)
		(fp_line
			(start -0.12065 -0.2794)
			(end 0.12065 -0.2794)
			(stroke
				(width 0.1)
				(type default)
			)
			(layer "F.Fab")
		)
		(fp_line
			(start -0.12065 -0.305054)
			(end -0.12065 -0.2794)
			(stroke
				(width 0.1)
				(type default)
			)
			(layer "F.Fab")
		)
		(fp_line
			(start -0.67945 0.3048)
			(end -0.67945 -0.305054)
			(stroke
				(width 0.1)
				(type default)
			)
			(layer "F.Fab")
		)
		(fp_line
			(start -0.67945 -0.305054)
			(end -0.12065 -0.305054)
			(stroke
				(width 0.1)
				(type default)
			)
			(layer "F.Fab")
		)
		(pad "1" smd circle
			(at -0.40005 0 180)
			(size 0 0)
			(layers "F.Cu" "F.Mask" "F.Paste")
			(net "SW_P12V_AUX_PVDDCR_CPU0_P0_FLT")
		)
		(pad "2" smd circle
			(at 0.40005 0 180)
			(size 0 0)
			(layers "F.Cu" "F.Mask" "F.Paste")
			(net "GND")
		)
	)
	(footprint ""
		(layer "F.Cu")
		(at 49.860454 -346.719398 -90)
		(property "Reference" "PC437_IOP1_1"
			(at 0 0 270)
			(layer "F.SilkS")
			(hide yes)
			(effects
				(font
					(size 1.27 1.27)
				)
			)
		)
		(property "Value" ""
			(at 0 0 270)
			(layer "F.Fab")
			(effects
				(font
					(size 1.27 1.27)
				)
			)
		)
		(duplicate_pad_numbers_are_jumpers no)
		(fp_line
			(start -0.7874 0.4064)
			(end -0.7874 -0.4064)
			(stroke
				(width 0.1524)
				(type default)
			)
			(layer "F.SilkS")
		)
		(fp_line
			(start 0.7874 0.4064)
			(end -0.7874 0.4064)
			(stroke
				(width 0.1524)
				(type default)
			)
			(layer "F.SilkS")
		)
		(fp_line
			(start -0.7874 -0.4064)
			(end 0.7874 -0.4064)
			(stroke
				(width 0.1524)
				(type default)
			)
			(layer "F.SilkS")
		)
		(fp_line
			(start 0.7874 -0.4064)
			(end 0.7874 0.4064)
			(stroke
				(width 0.1524)
				(type default)
			)
			(layer "F.SilkS")
		)
		(fp_line
			(start -0.67945 0.3048)
			(end -0.67945 -0.305054)
			(stroke
				(width 0.1)
				(type default)
			)
			(layer "F.Fab")
		)
		(fp_line
			(start -0.12065 0.3048)
			(end -0.67945 0.3048)
			(stroke
				(width 0.1)
				(type default)
			)
			(layer "F.Fab")
		)
		(fp_line
			(start 0.120396 0.3048)
			(end 0.120396 0.2794)
			(stroke
				(width 0.1)
				(type default)
			)
			(layer "F.Fab")
		)
		(fp_line
			(start 0.67945 0.3048)
			(end 0.120396 0.3048)
			(stroke
				(width 0.1)
				(type default)
			)
			(layer "F.Fab")
		)
		(fp_line
			(start -0.12065 0.2794)
			(end -0.12065 0.3048)
			(stroke
				(width 0.1)
				(type default)
			)
			(layer "F.Fab")
		)
		(fp_line
			(start 0.120396 0.2794)
			(end -0.12065 0.2794)
			(stroke
				(width 0.1)
				(type default)
			)
			(layer "F.Fab")
		)
		(fp_line
			(start -0.12065 -0.2794)
			(end 0.12065 -0.2794)
			(stroke
				(width 0.1)
				(type default)
			)
			(layer "F.Fab")
		)
		(fp_line
			(start 0.12065 -0.2794)
			(end 0.12065 -0.3048)
			(stroke
				(width 0.1)
				(type default)
			)
			(layer "F.Fab")
		)
		(fp_line
			(start 0.12065 -0.3048)
			(end 0.67945 -0.3048)
			(stroke
				(width 0.1)
				(type default)
			)
			(layer "F.Fab")
		)
		(fp_line
			(start 0.67945 -0.3048)
			(end 0.67945 0.3048)
			(stroke
				(width 0.1)
				(type default)
			)
			(layer "F.Fab")
		)
		(fp_line
			(start -0.67945 -0.305054)
			(end -0.12065 -0.305054)
			(stroke
				(width 0.1)
				(type default)
			)
			(layer "F.Fab")
		)
		(fp_line
			(start -0.12065 -0.305054)
			(end -0.12065 -0.2794)
			(stroke
				(width 0.1)
				(type default)
			)
			(layer "F.Fab")
		)
		(pad "1" smd circle
			(at -0.40005 0 270)
			(size 0 0)
			(layers "F.Cu" "F.Mask" "F.Paste")
			(net "PVDDCR_CPU1_P1_PVCC")
		)
		(pad "2" smd circle
			(at 0.40005 0 270)
			(size 0 0)
			(layers "F.Cu" "F.Mask" "F.Paste")
			(net "GND")
		)
	)
)
